# T6G (Grand Teton) — schematic netlist excerpt (pin names and nets, part order shuffled) for the footprints in the layout excerpt that follows; sources: Cadence DE-HDL packaged netlist, KiCad conversion of 04192023_DAF0TMB3IC0_F0TG_MB_C_brd_V02_OCP.brd

PR6801  Q_RES  2.2 1% CHIP  pkg 0402LF  page 361 : A = SW_P1V8_RETIMER_CPU1_BST ; B = SW_P1V8_RETIMER_CPU1_BST_R

(kicad_pcb
	(version 20260206)
	(generator "pcbnew")
	(generator_version "10.0")
	(general
		(thickness 1.6)
		(legacy_teardrops no)
	)
	(paper "A4")
	(title_block
		(title "04192023_DAF0TMB3IC0_F0TG_MB_C_brd_V02_OCP.brd")
		(comment 1 "Grand Teton / footprints 2421-2421 of 8354")
	)
	(layers
		(0 "F.Cu" signal "TOP")
		(4 "In1.Cu" signal "GND")
		(6 "In2.Cu" signal "IN1")
		(8 "In3.Cu" signal "GND1")
		(10 "In4.Cu" signal "IN2")
		(12 "In5.Cu" signal "GND2")
		(14 "In6.Cu" signal "IN3")
		(16 "In7.Cu" signal "GND3")
		(18 "In8.Cu" signal "VCC")
		(20 "In9.Cu" signal "VCC1")
		(22 "In10.Cu" signal "GND4")
		(24 "In11.Cu" signal "IN4")
		(26 "In12.Cu" signal "GND5")
		(28 "In13.Cu" signal "IN5")
		(30 "In14.Cu" signal "GND6")
		(32 "In15.Cu" signal "IN6")
		(34 "In16.Cu" signal "GND7")
		(2 "B.Cu" signal "BOTTOM")
		(9 "F.Adhes" user "F.Adhesive")
		(11 "B.Adhes" user "B.Adhesive")
		(13 "F.Paste" user "Package Geometry/Pastemask Top")
		(15 "B.Paste" user "Package Geometry/Pastemask Bottom")
		(5 "F.SilkS" user "Ref Des/Silkscreen Top")
		(7 "B.SilkS" user "Ref Des/Silkscreen Bottom")
		(1 "F.Mask" user "Board Geometry/Soldermask Top")
		(3 "B.Mask" user "Board Geometry/Soldermask Bottom")
		(17 "Dwgs.User" user "User.Drawings")
		(19 "Cmts.User" user "User.Comments")
		(21 "Eco1.User" user "User.Eco1")
		(23 "Eco2.User" user "User.Eco2")
		(25 "Edge.Cuts" user "Board Geometry/Outline")
		(27 "Margin" user)
		(31 "F.CrtYd" user "Package Geometry/Place Bound Top")
		(29 "B.CrtYd" user "Package Geometry/Place Bound Bottom")
		(35 "F.Fab" user "Ref Des/Assembly Top")
		(33 "B.Fab" user "Ref Des/Assembly Bottom")
	)
	(footprint ""
		(layer "F.Cu")
		(at 228.827076 -294.597074 180)
		(property "Reference" "PR6801"
			(at 0 0 180)
			(layer "F.SilkS")
			(hide yes)
			(effects
				(font
					(size 1.27 1.27)
				)
			)
		)
		(property "Value" ""
			(at 0 0 180)
			(layer "F.Fab")
			(effects
				(font
					(size 1.27 1.27)
				)
			)
		)
		(duplicate_pad_numbers_are_jumpers no)
		(fp_line
			(start 0.7874 0.4064)
			(end -0.7874 0.4064)
			(stroke
				(width 0.1524)
				(type default)
			)
			(layer "F.SilkS")
		)
		(fp_line
			(start 0.7874 -0.4064)
			(end 0.7874 0.4064)
			(stroke
				(width 0.1524)
				(type default)
			)
			(layer "F.SilkS")
		)
		(fp_line
			(start -0.7874 0.4064)
			(end -0.7874 -0.4064)
			(stroke
				(width 0.1524)
				(type default)
			)
			(layer "F.SilkS")
		)
		(fp_line
			(start -0.7874 -0.4064)
			(end 0.7874 -0.4064)
			(stroke
				(width 0.1524)
				(type default)
			)
			(layer "F.SilkS")
		)
		(fp_line
			(start 0.67945 0.3048)
			(end 0.120396 0.3048)
			(stroke
				(width 0.1)
				(type default)
			)
			(layer "F.Fab")
		)
		(fp_line
			(start 0.67945 -0.3048)
			(end 0.67945 0.3048)
			(stroke
				(width 0.1)
				(type default)
			)
			(layer "F.Fab")
		)
		(fp_line
			(start 0.12065 -0.2794)
			(end 0.12065 -0.3048)
			(stroke
				(width 0.1)
				(type default)
			)
			(layer "F.Fab")
		)
		(fp_line
			(start 0.12065 -0.3048)
			(end 0.67945 -0.3048)
			(stroke
				(width 0.1)
				(type default)
			)
			(layer "F.Fab")
		)
		(fp_line
			(start 0.120396 0.3048)
			(end 0.120396 0.2794)
			(stroke
				(width 0.1)
				(type default)
			)
			(layer "F.Fab")
		)
		(fp_line
			(start 0.120396 0.2794)
			(end -0.12065 0.2794)
			(stroke
				(width 0.1)
				(type default)
			)
			(layer "F.Fab")
		)
		(fp_line
			(start -0.12065 0.3048)
			(end -0.67945 0.3048)
			(stroke
				(width 0.1)
				(type default)
			)
			(layer "F.Fab")
		)
		(fp_line
			(start -0.12065 0.2794)
			(end -0.12065 0.3048)
			(stroke
				(width 0.1)
				(type default)
			)
			(layer "F.Fab")
		)
		(fp_line
			(start -0.12065 -0.2794)
			(end 0.12065 -0.2794)
			(stroke
				(width 0.1)
				(type default)
			)
			(layer "F.Fab")
		)
		(fp_line
			(start -0.12065 -0.305054)
			(end -0.12065 -0.2794)
			(stroke
				(width 0.1)
				(type default)
			)
			(layer "F.Fab")
		)
		(fp_line
			(start -0.67945 0.3048)
			(end -0.67945 -0.305054)
			(stroke
				(width 0.1)
				(type default)
			)
			(layer "F.Fab")
		)
		(fp_line
			(start -0.67945 -0.305054)
			(end -0.12065 -0.305054)
			(stroke
				(width 0.1)
				(type default)
			)
			(layer "F.Fab")
		)
		(pad "1" smd circle
			(at -0.40005 0 180)
			(size 0 0)
			(layers "F.Cu" "F.Mask" "F.Paste")
			(net "SW_P1V8_RETIMER_CPU1_BST")
		)
		(pad "2" smd circle
			(at 0.40005 0 180)
			(size 0 0)
			(layers "F.Cu" "F.Mask" "F.Paste")
			(net "SW_P1V8_RETIMER_CPU1_BST_R")
		)
	)
)
